(kicad_pcb
	(version 20241229)
	(generator "pcbnew")
	(generator_version "9.0")
	(general
		(thickness 1.711)
		(legacy_teardrops no)
	)
	(paper "A4")
	(title_block
		(title "Antmicro Baseboard for Jetson AGX Thor")
		(date "2026-02-18")
		(rev "1.1.0")
		(company "Antmicro Ltd")
		(comment 1 "www.antmicro.com")
		(comment 9 "footprints 990-994 of 1170")
	)
	(layers
		(0 "F.Cu" signal)
		(4 "In1.Cu" signal)
		(6 "In2.Cu" signal)
		(8 "In3.Cu" signal)
		(10 "In4.Cu" jumper)
		(12 "In5.Cu" signal)
		(14 "In6.Cu" signal)
		(16 "In7.Cu" signal)
		(18 "In8.Cu" signal)
		(2 "B.Cu" signal)
		(9 "F.Adhes" user "F.Adhesive")
		(11 "B.Adhes" user "B.Adhesive")
		(13 "F.Paste" user)
		(15 "B.Paste" user)
		(5 "F.SilkS" user "F.Silkscreen")
		(7 "B.SilkS" user "B.Silkscreen")
		(1 "F.Mask" user)
		(3 "B.Mask" user)
		(17 "Dwgs.User" user "User.Drawings")
		(19 "Cmts.User" user "User.Comments")
		(21 "Eco1.User" user "User.Eco1")
		(23 "Eco2.User" user "User.Eco2")
		(25 "Edge.Cuts" user)
		(27 "Margin" user)
		(31 "F.CrtYd" user "F.Courtyard")
		(29 "B.CrtYd" user "B.Courtyard")
		(35 "F.Fab" user)
		(33 "B.Fab" user)
	)
	(footprint "antmicro-footprints:C_0402_1005Metric"
		(layer "B.Cu")
		(at 234.6 84.1 180)
		(descr "Capacitor SMD 0402")
		(tags "capacitor SMD 0402")
		(property "Reference" "C148"
			(at -1.6 -1.4 0)
			(layer "B.SilkS")
			(effects
				(font
					(size 0.7 0.7)
					(thickness 0.15)
				)
				(justify left bottom mirror)
			)
		)
		(property "Value" "C_100n_0402"
			(at -1.022927 -2.155213 0)
			(layer "B.Fab")
			(effects
				(font
					(size 0.7 0.7)
					(thickness 0.15)
				)
				(justify left bottom mirror)
			)
		)
		(property "Datasheet" "https://www.murata.com/products/productdetail?partno=GRM155R61H104KE14%23"
			(at 0 0 0)
			(layer "B.Fab")
			(hide yes)
			(effects
				(font
					(size 1.27 1.27)
					(thickness 0.15)
				)
				(justify mirror)
			)
		)
		(property "Description" "SMD Multilayer Ceramic Capacitor, 0.1 µF, 50 V, 0402 [1005 Metric], ± 10%, X5R, GRM Series"
			(at 0 0 0)
			(layer "B.Fab")
			(hide yes)
			(effects
				(font
					(size 1.27 1.27)
					(thickness 0.15)
				)
				(justify mirror)
			)
		)
		(property "Manufacturer" "Murata"
			(at 0 0 0)
			(unlocked yes)
			(layer "B.Fab")
			(hide yes)
			(effects
				(font
					(size 1 1)
					(thickness 0.15)
				)
				(justify mirror)
			)
		)
		(property "MPN" "GRM155R61H104KE14D"
			(at 0 0 0)
			(unlocked yes)
			(layer "B.Fab")
			(hide yes)
			(effects
				(font
					(size 1 1)
					(thickness 0.15)
				)
				(justify mirror)
			)
		)
		(property "Val" "100n"
			(at 0 0 0)
			(unlocked yes)
			(layer "B.Fab")
			(hide yes)
			(effects
				(font
					(size 1 1)
					(thickness 0.15)
				)
				(justify mirror)
			)
		)
		(property "License" "Apache-2.0"
			(at 0 0 0)
			(unlocked yes)
			(layer "B.Fab")
			(hide yes)
			(effects
				(font
					(size 1 1)
					(thickness 0.15)
				)
				(justify mirror)
			)
		)
		(property "Author" "Antmicro"
			(at 0 0 0)
			(unlocked yes)
			(layer "B.Fab")
			(hide yes)
			(effects
				(font
					(size 1 1)
					(thickness 0.15)
				)
				(justify mirror)
			)
		)
		(property "Voltage" "50V"
			(at 0 0 0)
			(unlocked yes)
			(layer "B.Fab")
			(hide yes)
			(effects
				(font
					(size 1 1)
					(thickness 0.15)
				)
				(justify mirror)
			)
		)
		(property "Dielectric" "X5R"
			(at 0 0 0)
			(unlocked yes)
			(layer "B.Fab")
			(hide yes)
			(effects
				(font
					(size 1 1)
					(thickness 0.15)
				)
				(justify mirror)
			)
		)
		(sheetname "/USB Debug, PD/")
		(sheetfile "usb_debug_pd.kicad_sch")
		(attr smd)
		(fp_poly
			(pts
				(xy -0.925 0.47) (xy -0.925 -0.47) (xy 0.925 -0.47) (xy 0.925 0.47)
			)
			(stroke
				(width 0.05)
				(type default)
			)
			(fill no)
			(layer "B.CrtYd")
		)
		(fp_line
			(start 0.504 0.25)
			(end 0.504 -0.248)
			(stroke
				(width 0.15)
				(type solid)
			)
			(layer "B.Fab")
		)
		(fp_line
			(start 0.504 -0.248)
			(end -0.494 -0.248)
			(stroke
				(width 0.15)
				(type solid)
			)
			(layer "B.Fab")
		)
		(fp_line
			(start -0.494 0.25)
			(end 0.504 0.25)
			(stroke
				(width 0.15)
				(type solid)
			)
			(layer "B.Fab")
		)
		(fp_line
			(start -0.494 -0.248)
			(end -0.494 0.25)
			(stroke
				(width 0.15)
				(type solid)
			)
			(layer "B.Fab")
		)
		(fp_text user "License: Apache-2.0"
			(at -0.939 -5.799 0)
			(layer "B.Fab")
			(effects
				(font
					(size 0.7 0.7)
					(thickness 0.15)
				)
				(justify left bottom mirror)
			)
		)
		(fp_text user "Author: Antmicro"
			(at -0.939 -3.399 0)
			(layer "B.Fab")
			(effects
				(font
					(size 0.7 0.7)
					(thickness 0.15)
				)
				(justify left bottom mirror)
			)
		)
		(fp_text user "${REFERENCE}"
			(at -0.939 -4.599 0)
			(layer "B.Fab")
			(effects
				(font
					(size 0.7 0.7)
					(thickness 0.15)
				)
				(justify left bottom mirror)
			)
		)
		(pad "1" smd roundrect
			(at -0.48 0 180)
			(size 0.59 0.64)
			(layers "B.Cu" "B.Mask" "B.Paste")
			(roundrect_rratio 0.25)
			(net 5 "+5V")
			(pintype "passive")
		)
		(pad "2" smd roundrect
			(at 0.48 0 180)
			(size 0.59 0.64)
			(layers "B.Cu" "B.Mask" "B.Paste")
			(roundrect_rratio 0.25)
			(net 1 "GND")
			(pintype "passive")
		)
	)
	(footprint "antmicro-footprints:R_0402_1005Metric"
		(layer "B.Cu")
		(at 62.8 86 -90)
		(descr "Resistor SMD 0402")
		(tags "resistor SMD 0402")
		(property "Reference" "R182"
			(at -1.75 -2.45 90)
			(layer "B.SilkS")
			(effects
				(font
					(size 0.7 0.7)
					(thickness 0.15)
				)
				(justify left bottom mirror)
			)
		)
		(property "Value" "R_200R_0402"
			(at -1.011843 -1.772046 90)
			(layer "B.Fab")
			(effects
				(font
					(size 0.7 0.7)
					(thickness 0.15)
				)
				(justify left bottom mirror)
			)
		)
		(property "Datasheet" "https://www.bourns.com/docs/product-datasheets/cr.pdf"
			(at 0 0 90)
			(layer "B.Fab")
			(hide yes)
			(effects
				(font
					(size 1.27 1.27)
					(thickness 0.15)
				)
				(justify mirror)
			)
		)
		(property "Description" "SMD Chip Resistor, 200 ohm, ± 1%, 62.5 mW, 0402 [1005 Metric], Thick Film, General Purpose"
			(at 0 0 90)
			(layer "B.Fab")
			(hide yes)
			(effects
				(font
					(size 1.27 1.27)
					(thickness 0.15)
				)
				(justify mirror)
			)
		)
		(property "Manufacturer" "Bourns"
			(at 0 0 90)
			(unlocked yes)
			(layer "B.Fab")
			(hide yes)
			(effects
				(font
					(size 1 1)
					(thickness 0.15)
				)
				(justify mirror)
			)
		)
		(property "MPN" "CR0402-FX-2000GLF"
			(at 0 0 90)
			(unlocked yes)
			(layer "B.Fab")
			(hide yes)
			(effects
				(font
					(size 1 1)
					(thickness 0.15)
				)
				(justify mirror)
			)
		)
		(property "Val" "200R"
			(at 0 0 90)
			(unlocked yes)
			(layer "B.Fab")
			(hide yes)
			(effects
				(font
					(size 1 1)
					(thickness 0.15)
				)
				(justify mirror)
			)
		)
		(property "License" "Apache-2.0"
			(at 0 0 90)
			(unlocked yes)
			(layer "B.Fab")
			(hide yes)
			(effects
				(font
					(size 1 1)
					(thickness 0.15)
				)
				(justify mirror)
			)
		)
		(property "Author" "Antmicro"
			(at 0 0 90)
			(unlocked yes)
			(layer "B.Fab")
			(hide yes)
			(effects
				(font
					(size 1 1)
					(thickness 0.15)
				)
				(justify mirror)
			)
		)
		(property "Tolerance" "1%"
			(at 0 0 90)
			(unlocked yes)
			(layer "B.Fab")
			(hide yes)
			(effects
				(font
					(size 1 1)
					(thickness 0.15)
				)
				(justify mirror)
			)
		)
		(sheetname "/CSI/")
		(sheetfile "csi.kicad_sch")
		(attr smd)
		(fp_poly
			(pts
				(xy -0.925 0.47) (xy 0.925 0.47) (xy 0.925 -0.47) (xy -0.925 -0.47)
			)
			(stroke
				(width 0.05)
				(type default)
			)
			(fill no)
			(layer "B.CrtYd")
		)
		(fp_poly
			(pts
				(xy -0.5 0.25) (xy 0.5 0.25) (xy 0.5 -0.25) (xy -0.5 -0.25)
			)
			(stroke
				(width 0.15)
				(type solid)
			)
			(fill no)
			(layer "B.Fab")
		)
		(fp_text user "Author: Antmicro"
			(at -0.95 -4.169 90)
			(layer "B.Fab")
			(effects
				(font
					(size 0.7 0.7)
					(thickness 0.15)
				)
				(justify left bottom mirror)
			)
		)
		(fp_text user "License: Apache-2.0"
			(at -0.949999 -5.169 90)
			(layer "B.Fab")
			(effects
				(font
					(size 0.7 0.7)
					(thickness 0.15)
				)
				(justify left bottom mirror)
			)
		)
		(fp_text user "${REFERENCE}"
			(at -0.95 -3.168 90)
			(layer "B.Fab")
			(effects
				(font
					(size 0.7 0.7)
					(thickness 0.15)
				)
				(justify left bottom mirror)
			)
		)
		(pad "1" smd roundrect
			(at -0.48 0 270)
			(size 0.59 0.64)
			(layers "B.Cu" "B.Mask" "B.Paste")
			(roundrect_rratio 0.25)
			(net 541 "Net-(D28-A)")
			(pintype "passive")
		)
		(pad "2" smd roundrect
			(at 0.48 0 270)
			(size 0.59 0.64)
			(layers "B.Cu" "B.Mask" "B.Paste")
			(roundrect_rratio 0.25)
			(net 6 "/CSI/CSIA_3V3")
			(pintype "passive")
		)
	)
	(footprint "antmicro-footprints:R_0402_1005Metric"
		(layer "B.Cu")
		(at 129.1 151.2 -90)
		(descr "Resistor SMD 0402")
		(tags "resistor SMD 0402")
		(property "Reference" "R230"
			(at -1.1 -6.29 90)
			(layer "B.SilkS")
			(effects
				(font
					(size 0.7 0.7)
					(thickness 0.15)
				)
				(justify left bottom mirror)
			)
		)
		(property "Value" "R_10k_0402"
			(at -1.011843 -1.772047 90)
			(layer "B.Fab")
			(effects
				(font
					(size 0.7 0.7)
					(thickness 0.15)
				)
				(justify left bottom mirror)
			)
		)
		(property "Datasheet" "https://www.bourns.com/docs/product-datasheets/cr.pdf"
			(at 0 0 90)
			(layer "B.Fab")
			(hide yes)
			(effects
				(font
					(size 1.27 1.27)
					(thickness 0.15)
				)
				(justify mirror)
			)
		)
		(property "Description" "SMD Chip Resistor, 10 kohm, ± 1%, 62.5 mW, 0402 [1005 Metric], Thick Film, General Purpose"
			(at 0 0 90)
			(layer "B.Fab")
			(hide yes)
			(effects
				(font
					(size 1.27 1.27)
					(thickness 0.15)
				)
				(justify mirror)
			)
		)
		(property "MPN" "CR0402-FX-1002GLF"
			(at 0 0 90)
			(unlocked yes)
			(layer "B.Fab")
			(hide yes)
			(effects
				(font
					(size 1 1)
					(thickness 0.15)
				)
				(justify mirror)
			)
		)
		(property "Manufacturer" "Bourns"
			(at 0 0 90)
			(unlocked yes)
			(layer "B.Fab")
			(hide yes)
			(effects
				(font
					(size 1 1)
					(thickness 0.15)
				)
				(justify mirror)
			)
		)
		(property "License" "Apache-2.0"
			(at 0 0 90)
			(unlocked yes)
			(layer "B.Fab")
			(hide yes)
			(effects
				(font
					(size 1 1)
					(thickness 0.15)
				)
				(justify mirror)
			)
		)
		(property "Author" "Antmicro"
			(at 0 0 90)
			(unlocked yes)
			(layer "B.Fab")
			(hide yes)
			(effects
				(font
					(size 1 1)
					(thickness 0.15)
				)
				(justify mirror)
			)
		)
		(property "Val" "10k"
			(at 0 0 90)
			(unlocked yes)
			(layer "B.Fab")
			(hide yes)
			(effects
				(font
					(size 1 1)
					(thickness 0.15)
				)
				(justify mirror)
			)
		)
		(property "Tolerance" "1%"
			(at 0 0 90)
			(unlocked yes)
			(layer "B.Fab")
			(hide yes)
			(effects
				(font
					(size 1 1)
					(thickness 0.15)
				)
				(justify mirror)
			)
		)
		(sheetname "/Peripherals/")
		(sheetfile "peripherals.kicad_sch")
		(attr smd)
		(fp_rect
			(start -0.925 0.47)
			(end 0.925 -0.47)
			(stroke
				(width 0.05)
				(type default)
			)
			(fill no)
			(layer "B.CrtYd")
		)
		(fp_rect
			(start -0.5 0.25)
			(end 0.5 -0.25)
			(stroke
				(width 0.15)
				(type solid)
			)
			(fill no)
			(layer "B.Fab")
		)
		(fp_text user "${REFERENCE}"
			(at -0.95 -3.168 90)
			(layer "B.Fab")
			(effects
				(font
					(size 0.7 0.7)
					(thickness 0.15)
				)
				(justify left bottom mirror)
			)
		)
		(fp_text user "License: Apache-2.0"
			(at -0.95 -5.169 90)
			(layer "B.Fab")
			(effects
				(font
					(size 0.7 0.7)
					(thickness 0.15)
				)
				(justify left bottom mirror)
			)
		)
		(fp_text user "Author: Antmicro"
			(at -0.95 -4.169 90)
			(layer "B.Fab")
			(effects
				(font
					(size 0.7 0.7)
					(thickness 0.15)
				)
				(justify left bottom mirror)
			)
		)
		(pad "1" smd roundrect
			(at -0.48 0 270)
			(size 0.59 0.64)
			(layers "B.Cu" "B.Mask" "B.Paste")
			(roundrect_rratio 0.25)
			(net 149 "/Peripherals/TPM_IRQ")
			(pintype "passive")
		)
		(pad "2" smd roundrect
			(at 0.48 0 270)
			(size 0.59 0.64)
			(layers "B.Cu" "B.Mask" "B.Paste")
			(roundrect_rratio 0.25)
			(net 2 "+3V3")
			(pintype "passive")
		)
	)
	(footprint "antmicro-footprints:R_0402_1005Metric"
		(layer "B.Cu")
		(at 206.7 121)
		(descr "Resistor SMD 0402")
		(tags "resistor SMD 0402")
		(property "Reference" "R263"
			(at 1.04 -0.35 0)
			(layer "B.SilkS")
			(effects
				(font
					(size 0.7 0.7)
					(thickness 0.15)
				)
				(justify right top mirror)
			)
		)
		(property "Value" "R_43k_0402"
			(at -1.011843 -1.772047 0)
			(layer "B.Fab")
			(effects
				(font
					(size 0.7 0.7)
					(thickness 0.15)
				)
				(justify right top mirror)
			)
		)
		(property "Datasheet" "https://www.bourns.com/docs/product-datasheets/cr.pdf"
			(at 0 0 0)
			(layer "B.Fab")
			(hide yes)
			(effects
				(font
					(size 1.27 1.27)
					(thickness 0.15)
				)
				(justify mirror)
			)
		)
		(property "Description" "SMD Chip Resistor"
			(at 0 0 0)
			(layer "B.Fab")
			(hide yes)
			(effects
				(font
					(size 1.27 1.27)
					(thickness 0.15)
				)
				(justify mirror)
			)
		)
		(property "MPN" "CR0402-FX-4302GLF"
			(at 0 0 180)
			(unlocked yes)
			(layer "B.Fab")
			(hide yes)
			(effects
				(font
					(size 1 1)
					(thickness 0.15)
				)
				(justify mirror)
			)
		)
		(property "Manufacturer" "Bourns"
			(at 0 0 180)
			(unlocked yes)
			(layer "B.Fab")
			(hide yes)
			(effects
				(font
					(size 1 1)
					(thickness 0.15)
				)
				(justify mirror)
			)
		)
		(property "License" "Apache-2.0"
			(at 0 0 180)
			(unlocked yes)
			(layer "B.Fab")
			(hide yes)
			(effects
				(font
					(size 1 1)
					(thickness 0.15)
				)
				(justify mirror)
			)
		)
		(property "Author" "Antmicro"
			(at 0 0 180)
			(unlocked yes)
			(layer "B.Fab")
			(hide yes)
			(effects
				(font
					(size 1 1)
					(thickness 0.15)
				)
				(justify mirror)
			)
		)
		(property "Val" "43k"
			(at 0 0 180)
			(unlocked yes)
			(layer "B.Fab")
			(hide yes)
			(effects
				(font
					(size 1 1)
					(thickness 0.15)
				)
				(justify mirror)
			)
		)
		(property "Tolerance" "1%"
			(at 0 0 180)
			(unlocked yes)
			(layer "B.Fab")
			(hide yes)
			(effects
				(font
					(size 1 1)
					(thickness 0.15)
				)
				(justify mirror)
			)
		)
		(sheetname "/USB Hub/")
		(sheetfile "usb_hub.kicad_sch")
		(attr smd)
		(fp_rect
			(start -0.925 0.47)
			(end 0.925 -0.47)
			(stroke
				(width 0.05)
				(type default)
			)
			(fill no)
			(layer "B.CrtYd")
		)
		(fp_rect
			(start -0.5 0.25)
			(end 0.5 -0.25)
			(stroke
				(width 0.15)
				(type solid)
			)
			(fill no)
			(layer "B.Fab")
		)
		(fp_text user "Author: Antmicro"
			(at -0.95 -4.169 0)
			(layer "B.Fab")
			(effects
				(font
					(size 0.7 0.7)
					(thickness 0.15)
				)
				(justify right top mirror)
			)
		)
		(fp_text user "License: Apache-2.0"
			(at -0.95 -5.169 0)
			(layer "B.Fab")
			(effects
				(font
					(size 0.7 0.7)
					(thickness 0.15)
				)
				(justify right top mirror)
			)
		)
		(fp_text user "${REFERENCE}"
			(at -0.95 -3.168 0)
			(layer "B.Fab")
			(effects
				(font
					(size 0.7 0.7)
					(thickness 0.15)
				)
				(justify right top mirror)
			)
		)
		(pad "1" smd roundrect
			(at -0.48 0)
			(size 0.59 0.64)
			(layers "B.Cu" "B.Mask" "B.Paste")
			(roundrect_rratio 0.25)
			(net 1016 "/USB Hub/USBC3_VBUS_MON")
			(pintype "passive")
		)
		(pad "2" smd roundrect
			(at 0.48 0)
			(size 0.59 0.64)
			(layers "B.Cu" "B.Mask" "B.Paste")
			(roundrect_rratio 0.25)
			(net 71 "/USB Hub/USBC3_VBUS")
			(pintype "passive")
		)
	)
	(footprint "antmicro-footprints:R_0402_1005Metric"
		(layer "B.Cu")
		(at 190 121.7 90)
		(descr "Resistor SMD 0402")
		(tags "resistor SMD 0402")
		(property "Reference" "R101"
			(at -3.7 -0.4 90)
			(layer "B.SilkS")
			(effects
				(font
					(size 0.7 0.7)
					(thickness 0.15)
				)
				(justify right top mirror)
			)
		)
		(property "Value" "R_0R_0402"
			(at -1.011843 -1.772047 90)
			(layer "B.Fab")
			(effects
				(font
					(size 0.7 0.7)
					(thickness 0.15)
				)
				(justify right top mirror)
			)
		)
		(property "Datasheet" "https://industrial.panasonic.com/cdbs/www-data/pdf/RDA0000/AOA0000C301.pdf"
			(at 0 0 90)
			(layer "B.Fab")
			(hide yes)
			(effects
				(font
					(size 1.27 1.27)
					(thickness 0.15)
				)
				(justify mirror)
			)
		)
		(property "Description" "SMD Chip Resistor, Jumper, 0 ohm, 100 mW, 0402 [1005 Metric], Thick Film, General Purpose"
			(at 0 0 90)
			(layer "B.Fab")
			(hide yes)
			(effects
				(font
					(size 1.27 1.27)
					(thickness 0.15)
				)
				(justify mirror)
			)
		)
		(property "MPN" "ERJ2GE0R00X"
			(at 0 0 270)
			(unlocked yes)
			(layer "B.Fab")
			(hide yes)
			(effects
				(font
					(size 1 1)
					(thickness 0.15)
				)
				(justify mirror)
			)
		)
		(property "Manufacturer" "Panasonic"
			(at 0 0 270)
			(unlocked yes)
			(layer "B.Fab")
			(hide yes)
			(effects
				(font
					(size 1 1)
					(thickness 0.15)
				)
				(justify mirror)
			)
		)
		(property "License" "Apache-2.0"
			(at 0 0 270)
			(unlocked yes)
			(layer "B.Fab")
			(hide yes)
			(effects
				(font
					(size 1 1)
					(thickness 0.15)
				)
				(justify mirror)
			)
		)
		(property "Author" "Antmicro"
			(at 0 0 270)
			(unlocked yes)
			(layer "B.Fab")
			(hide yes)
			(effects
				(font
					(size 1 1)
					(thickness 0.15)
				)
				(justify mirror)
			)
		)
		(property "Val" "0R"
			(at 0 0 270)
			(unlocked yes)
			(layer "B.Fab")
			(hide yes)
			(effects
				(font
					(size 1 1)
					(thickness 0.15)
				)
				(justify mirror)
			)
		)
		(property "Tolerance" "~"
			(at 0 0 270)
			(unlocked yes)
			(layer "B.Fab")
			(hide yes)
			(effects
				(font
					(size 1 1)
					(thickness 0.15)
				)
				(justify mirror)
			)
		)
		(property "Current" "1A"
			(at 0 0 270)
			(unlocked yes)
			(layer "B.Fab")
			(hide yes)
			(effects
				(font
					(size 1 1)
					(thickness 0.15)
				)
				(justify mirror)
			)
		)
		(sheetname "/USB Debug, PD/")
		(sheetfile "usb_debug_pd.kicad_sch")
		(attr smd exclude_from_pos_files exclude_from_bom dnp)
		(fp_rect
			(start -0.925 0.47)
			(end 0.925 -0.47)
			(stroke
				(width 0.05)
				(type default)
			)
			(fill no)
			(layer "B.CrtYd")
		)
		(fp_rect
			(start -0.5 0.25)
			(end 0.5 -0.25)
			(stroke
				(width 0.15)
				(type solid)
			)
			(fill no)
			(layer "B.Fab")
		)
		(fp_text user "Author: Antmicro"
			(at -0.95 -4.169 90)
			(layer "B.Fab")
			(effects
				(font
					(size 0.7 0.7)
					(thickness 0.15)
				)
				(justify right top mirror)
			)
		)
		(fp_text user "License: Apache-2.0"
			(at -0.95 -5.169 90)
			(layer "B.Fab")
			(effects
				(font
					(size 0.7 0.7)
					(thickness 0.15)
				)
				(justify right top mirror)
			)
		)
		(fp_text user "${REFERENCE}"
			(at -0.95 -3.168 90)
			(layer "B.Fab")
			(effects
				(font
					(size 0.7 0.7)
					(thickness 0.15)
				)
				(justify right top mirror)
			)
		)
		(pad "1" smd roundrect
			(at -0.48 0 90)
			(size 0.59 0.64)
			(layers "B.Cu" "B.Mask" "B.Paste")
			(roundrect_rratio 0.25)
			(net 811 "/USB Debug, PD/MOSI")
			(pintype "passive")
		)
		(pad "2" smd roundrect
			(at 0.48 0 90)
			(size 0.59 0.64)
			(layers "B.Cu" "B.Mask" "B.Paste")
			(roundrect_rratio 0.25)
			(net 926 "/USB Debug, PD/SPI_{HUB_DEBUG}.MOSI")
			(pintype "passive")
		)
	)
)
